(kicad_pcb
	(version 20260206)
	(generator "pcbnew")
	(generator_version "10.0")
	(general
		(thickness 1.6)
		(legacy_teardrops no)
	)
	(paper "A4")
	(title_block
		(title "Bryce Canyon_SCC_16316-1_OCP.brd")
		(comment 1 "Bryce Canyon / footprints 1-8 of 1561")
	)
	(layers
		(0 "F.Cu" signal "TOP")
		(4 "In1.Cu" signal "L2GND")
		(6 "In2.Cu" signal "L3")
		(8 "In3.Cu" signal "L4VCC")
		(10 "In4.Cu" signal "L5VCC")
		(12 "In5.Cu" signal "L6")
		(14 "In6.Cu" signal "L7GND")
		(2 "B.Cu" signal "BOTTOM")
		(9 "F.Adhes" user "F.Adhesive")
		(11 "B.Adhes" user "B.Adhesive")
		(13 "F.Paste" user "Package Geometry/Pastemask Top")
		(15 "B.Paste" user "Package Geometry/Pastemask Bottom")
		(5 "F.SilkS" user "Ref Des/Silkscreen Top")
		(7 "B.SilkS" user "Ref Des/Silkscreen Bottom")
		(1 "F.Mask" user "Board Geometry/Soldermask Top")
		(3 "B.Mask" user "Board Geometry/Soldermask Bottom")
		(17 "Dwgs.User" user "User.Drawings")
		(19 "Cmts.User" user "User.Comments")
		(21 "Eco1.User" user "User.Eco1")
		(23 "Eco2.User" user "User.Eco2")
		(25 "Edge.Cuts" user "Board Geometry/Outline")
		(27 "Margin" user)
		(31 "F.CrtYd" user "Package Geometry/Place Bound Top")
		(29 "B.CrtYd" user "Package Geometry/Place Bound Bottom")
		(35 "F.Fab" user "Ref Des/Assembly Top")
		(33 "B.Fab" user "Ref Des/Assembly Bottom")
	)
	(footprint ""
		(layer "F.Cu")
		(at 58.70575 -123.205494)
		(property "Reference" "R510"
			(at 0 0 0)
			(layer "F.SilkS")
			(hide yes)
			(effects
				(font
					(size 1.27 1.27)
				)
			)
		)
		(property "Value" "0R5J-5-GP"
			(at 0 -8.9535 0)
			(unlocked yes)
			(layer "F.Fab")
			(hide yes)
			(effects
				(font
					(size 1.27 1.016)
					(thickness 0.1524)
				)
			)
		)
		(property "Device Type" "R805H24"
			(at 0 -10.6299 0)
			(unlocked yes)
			(layer "F.Fab")
			(hide yes)
			(effects
				(font
					(size 1.27 1.016)
					(thickness 0.1524)
				)
			)
		)
		(duplicate_pad_numbers_are_jumpers no)
		(fp_line
			(start -0.889 -1.7018)
			(end -0.889 0.2794)
			(stroke
				(width 0.1524)
				(type default)
			)
			(layer "F.SilkS")
		)
		(fp_line
			(start -0.889 0.0762)
			(end -0.889 1.7018)
			(stroke
				(width 0.1524)
				(type default)
			)
			(layer "F.SilkS")
		)
		(fp_line
			(start -0.889 1.7018)
			(end 0.889 1.7018)
			(stroke
				(width 0.1524)
				(type default)
			)
			(layer "F.SilkS")
		)
		(fp_line
			(start 0.889 -1.7018)
			(end -0.889 -1.7018)
			(stroke
				(width 0.1524)
				(type default)
			)
			(layer "F.SilkS")
		)
		(fp_line
			(start 0.889 -1.7018)
			(end 0.889 -0.381)
			(stroke
				(width 0.1524)
				(type default)
			)
			(layer "F.SilkS")
		)
		(fp_line
			(start 0.889 1.7018)
			(end 0.889 -0.508)
			(stroke
				(width 0.1524)
				(type default)
			)
			(layer "F.SilkS")
		)
		(fp_poly
			(pts
				(xy 0.9652 -1.778) (xy 0.9652 1.778) (xy -0.9652 1.778) (xy -0.9652 -1.778)
			)
			(stroke
				(width 0)
				(type default)
			)
			(fill no)
			(layer "F.CrtYd")
		)
		(fp_rect
			(start -0.9652 1.778)
			(end 0.9652 -1.778)
			(stroke
				(width 0)
				(type default)
			)
			(fill no)
			(layer "F.Fab")
		)
		(pad "1" smd rect
			(at 0 -0.9652)
			(size 1.397 1.143)
			(layers "F.Cu" "F.Mask" "F.Paste")
			(net "P3V3")
		)
		(pad "2" smd rect
			(at 0 0.9652)
			(size 1.397 1.143)
			(layers "F.Cu" "F.Mask" "F.Paste")
			(net "P3V3_OUT")
		)
	)
	(footprint ""
		(layer "F.Cu")
		(at 148.436838 -54.426104 102)
		(property "Reference" "C344"
			(at 0 0 102)
			(layer "F.SilkS")
			(hide yes)
			(effects
				(font
					(size 1.27 1.27)
				)
			)
		)
		(property "Value" "SCD01U16V1KX-GP"
			(at -2.832244 -1.740078 102)
			(unlocked yes)
			(layer "F.Fab")
			(hide yes)
			(effects
				(font
					(size 1.016 1.016)
					(thickness 0.1524)
				)
			)
		)
		(property "Device Type" "C0201H13"
			(at -2.832121 -3.264082 102)
			(unlocked yes)
			(layer "F.Fab")
			(hide yes)
			(effects
				(font
					(size 1.016 1.016)
					(thickness 0.1524)
				)
			)
		)
		(duplicate_pad_numbers_are_jumpers no)
		(fp_poly
			(pts
				(xy -0.279454 -0.647706) (xy 0.279346 -0.647706) (xy 0.279346 0.647694) (xy -0.279454 0.647694)
			)
			(stroke
				(width 0)
				(type default)
			)
			(fill no)
			(layer "F.CrtYd")
		)
		(fp_poly
			(pts
				(xy -0.279454 -0.647706) (xy 0.279346 -0.647706) (xy 0.279346 0.647694) (xy -0.279454 0.647694)
			)
			(stroke
				(width 0)
				(type default)
			)
			(fill no)
			(layer "F.Fab")
		)
		(pad "1" smd custom
			(at -0.000001 -0.2794 102)
			(size 0.0762 0.0762)
			(layers "F.Cu" "F.Mask" "F.Paste")
			(net "PHY_SCC_TO_IOC_47_DN")
			(options
				(clearance outline)
				(anchor circle)
			)
			(primitives
				(gr_poly
					(pts
						(arc
							(start 0.1524 -0.127)
							(mid 0.137521 -0.162921)
							(end 0.1016 -0.1778)
						)
						(arc
							(start -0.1016 -0.1778)
							(mid -0.137521 -0.162921)
							(end -0.1524 -0.127)
						)
						(arc
							(start -0.1524 0.127)
							(mid -0.137521 0.162921)
							(end -0.1016 0.1778)
						)
						(arc
							(start 0.1016 0.1778)
							(mid 0.137521 0.162921)
							(end 0.1524 0.127)
						)
					)
					(width 0)
					(fill yes)
				)
			)
		)
		(pad "2" smd custom
			(at 0.000001 0.2794 102)
			(size 0.0762 0.0762)
			(layers "F.Cu" "F.Mask" "F.Paste")
			(net "PHY_SCC_TO_IOC_C_47_DN")
			(options
				(clearance outline)
				(anchor circle)
			)
			(primitives
				(gr_poly
					(pts
						(arc
							(start 0.1524 -0.127)
							(mid 0.137521 -0.162921)
							(end 0.1016 -0.1778)
						)
						(arc
							(start -0.1016 -0.1778)
							(mid -0.137521 -0.162921)
							(end -0.1524 -0.127)
						)
						(arc
							(start -0.1524 0.127)
							(mid -0.137521 0.162921)
							(end -0.1016 0.1778)
						)
						(arc
							(start 0.1016 0.1778)
							(mid 0.137521 0.162921)
							(end 0.1524 0.127)
						)
					)
					(width 0)
					(fill yes)
				)
			)
		)
	)
	(footprint ""
		(layer "F.Cu")
		(at 165.4556 -90.0176 90)
		(property "Reference" "C657"
			(at 0 0 90)
			(layer "F.SilkS")
			(hide yes)
			(effects
				(font
					(size 1.27 1.27)
				)
			)
		)
		(property "Value" "SC10U16V5KX-7-GP-U"
			(at -0.0762 -6.1214 90)
			(unlocked yes)
			(layer "F.Fab")
			(hide yes)
			(effects
				(font
					(size 1.016 1.016)
					(thickness 0.1524)
				)
			)
		)
		(property "Device Type" "C805H58"
			(at -0.0762 -8.1534 90)
			(unlocked yes)
			(layer "F.Fab")
			(hide yes)
			(effects
				(font
					(size 1.016 1.016)
					(thickness 0.1524)
				)
			)
		)
		(duplicate_pad_numbers_are_jumpers no)
		(fp_line
			(start 0.635 0)
			(end -0.635 0)
			(stroke
				(width 0.508)
				(type default)
			)
			(layer "F.SilkS")
		)
		(fp_rect
			(start -0.9652 1.778)
			(end 0.9652 -1.778)
			(stroke
				(width 0)
				(type default)
			)
			(fill no)
			(layer "F.CrtYd")
		)
		(fp_poly
			(pts
				(xy -0.9652 -1.778) (xy 0.9652 -1.778) (xy 0.9652 1.778) (xy -0.9652 1.778)
			)
			(stroke
				(width 0)
				(type default)
			)
			(fill no)
			(layer "F.Fab")
		)
		(pad "1" smd rect
			(at 0 -0.9652 90)
			(size 1.397 1.143)
			(layers "F.Cu" "F.Mask" "F.Paste")
			(net "P12V_SYBY_VDD_U6")
		)
		(pad "2" smd rect
			(at 0 0.9652 90)
			(size 1.397 1.143)
			(layers "F.Cu" "F.Mask" "F.Paste")
			(net "GND")
		)
	)
	(footprint ""
		(layer "F.Cu")
		(at 143.891 -100.457)
		(property "Reference" "R134"
			(at 0 0 0)
			(layer "F.SilkS")
			(hide yes)
			(effects
				(font
					(size 1.27 1.27)
				)
			)
		)
		(property "Value" "D51R3F-2-GP"
			(at -0.0254 -2.5146 0)
			(unlocked yes)
			(layer "F.Fab")
			(hide yes)
			(effects
				(font
					(size 1.016 1.016)
					(thickness 0.1524)
				)
			)
		)
		(property "Device Type" "R603H22"
			(at -0.0254 -4.0386 0)
			(unlocked yes)
			(layer "F.Fab")
			(hide yes)
			(effects
				(font
					(size 1.016 1.016)
					(thickness 0.1524)
				)
			)
		)
		(duplicate_pad_numbers_are_jumpers no)
		(fp_line
			(start -0.4826 0)
			(end -0.2032 0)
			(stroke
				(width 0.2032)
				(type default)
			)
			(layer "F.SilkS")
		)
		(fp_line
			(start 0.2032 0)
			(end 0.4826 0)
			(stroke
				(width 0.2032)
				(type default)
			)
			(layer "F.SilkS")
		)
		(fp_rect
			(start -0.5842 1.3335)
			(end 0.5842 -1.3335)
			(stroke
				(width 0)
				(type default)
			)
			(fill no)
			(layer "F.CrtYd")
		)
		(fp_rect
			(start -0.5842 1.3335)
			(end 0.5842 -1.3335)
			(stroke
				(width 0)
				(type default)
			)
			(fill no)
			(layer "F.Fab")
		)
		(pad "1" smd custom
			(at 0 -0.762)
			(size 0.2159 0.2159)
			(layers "F.Cu" "F.Mask" "F.Paste")
			(net "P1V5_E")
			(options
				(clearance outline)
				(anchor circle)
			)
			(primitives
				(gr_poly
					(pts
						(arc
							(start -0.3302 -0.4318)
							(mid -0.402042 -0.402042)
							(end -0.4318 -0.3302)
						)
						(arc
							(start -0.4318 0.3302)
							(mid -0.402042 0.402042)
							(end -0.3302 0.4318)
						)
						(arc
							(start 0.3302 0.4318)
							(mid 0.402042 0.402042)
							(end 0.4318 0.3302)
						)
						(arc
							(start 0.4318 -0.3302)
							(mid 0.402042 -0.402042)
							(end 0.3302 -0.4318)
						)
					)
					(width 0)
					(fill yes)
				)
			)
		)
		(pad "2" smd custom
			(at 0 0.762)
			(size 0.2159 0.2159)
			(layers "F.Cu" "F.Mask" "F.Paste")
			(net "GB_VDDH")
			(options
				(clearance outline)
				(anchor circle)
			)
			(primitives
				(gr_poly
					(pts
						(arc
							(start -0.3302 -0.4318)
							(mid -0.402042 -0.402042)
							(end -0.4318 -0.3302)
						)
						(arc
							(start -0.4318 0.3302)
							(mid -0.402042 0.402042)
							(end -0.3302 0.4318)
						)
						(arc
							(start 0.3302 0.4318)
							(mid 0.402042 0.402042)
							(end 0.4318 0.3302)
						)
						(arc
							(start 0.4318 -0.3302)
							(mid 0.402042 -0.402042)
							(end 0.3302 -0.4318)
						)
					)
					(width 0)
					(fill yes)
				)
			)
		)
	)
	(footprint ""
		(layer "F.Cu")
		(at 192.791842 -24.74976)
		(property "Reference" "TP131"
			(at 0 0 0)
			(layer "F.SilkS")
			(hide yes)
			(effects
				(font
					(size 1.27 1.27)
				)
			)
		)
		(property "Value" "TPAD28-2-GP"
			(at -0.0127 -1.6637 0)
			(unlocked yes)
			(layer "F.Fab")
			(hide yes)
			(effects
				(font
					(size 1.016 1.016)
					(thickness 0.1524)
				)
			)
		)
		(property "Device Type" "TPAD28"
			(at -0.0127 -3.1877 0)
			(unlocked yes)
			(layer "F.Fab")
			(hide yes)
			(effects
				(font
					(size 1.016 1.016)
					(thickness 0.1524)
				)
			)
		)
		(duplicate_pad_numbers_are_jumpers no)
		(fp_poly
			(pts
				(arc
					(start 0.3556 0)
					(mid -0.3556 0)
					(end 0.3556 0)
				)
			)
			(stroke
				(width 0)
				(type default)
			)
			(fill no)
			(layer "F.CrtYd")
		)
		(fp_poly
			(pts
				(arc
					(start 0.6096 0)
					(mid -0.6096 0)
					(end 0.6096 0)
				)
			)
			(stroke
				(width 0)
				(type default)
			)
			(fill no)
			(layer "F.Fab")
		)
		(pad "1" smd circle
			(at 0 0)
			(size 0.7112 0.7112)
			(layers "F.Cu" "F.Mask" "F.Paste")
			(net "SYS_HALT1#")
		)
	)
	(footprint ""
		(layer "F.Cu")
		(at 142.57782 -59.940952 -90)
		(property "Reference" "C37"
			(at 0 0 270)
			(layer "F.SilkS")
			(hide yes)
			(effects
				(font
					(size 1.27 1.27)
				)
			)
		)
		(property "Value" "SCD01U16V1KX-GP"
			(at -2.8321 -1.7399 270)
			(unlocked yes)
			(layer "F.Fab")
			(hide yes)
			(effects
				(font
					(size 1.016 1.016)
					(thickness 0.1524)
				)
			)
		)
		(property "Device Type" "C0201H13"
			(at -2.8321 -3.2639 270)
			(unlocked yes)
			(layer "F.Fab")
			(hide yes)
			(effects
				(font
					(size 1.016 1.016)
					(thickness 0.1524)
				)
			)
		)
		(duplicate_pad_numbers_are_jumpers no)
		(fp_rect
			(start -0.2794 0.6477)
			(end 0.2794 -0.6477)
			(stroke
				(width 0)
				(type default)
			)
			(fill no)
			(layer "F.CrtYd")
		)
		(fp_rect
			(start -0.2794 0.6477)
			(end 0.2794 -0.6477)
			(stroke
				(width 0)
				(type default)
			)
			(fill no)
			(layer "F.Fab")
		)
		(pad "1" smd custom
			(at 0 -0.2794 270)
			(size 0.0762 0.0762)
			(layers "F.Cu" "F.Mask" "F.Paste")
			(net "PHY_IOC_TO_SCC_45_DP")
			(options
				(clearance outline)
				(anchor circle)
			)
			(primitives
				(gr_poly
					(pts
						(arc
							(start 0.1524 -0.127)
							(mid 0.137521 -0.162921)
							(end 0.1016 -0.1778)
						)
						(arc
							(start -0.1016 -0.1778)
							(mid -0.137521 -0.162921)
							(end -0.1524 -0.127)
						)
						(arc
							(start -0.1524 0.127)
							(mid -0.137521 0.162921)
							(end -0.1016 0.1778)
						)
						(arc
							(start 0.1016 0.1778)
							(mid 0.137521 0.162921)
							(end 0.1524 0.127)
						)
					)
					(width 0)
					(fill yes)
				)
			)
		)
		(pad "2" smd custom
			(at 0 0.2794 270)
			(size 0.0762 0.0762)
			(layers "F.Cu" "F.Mask" "F.Paste")
			(net "PHY_IOC_TO_SCC_C_45_DP")
			(options
				(clearance outline)
				(anchor circle)
			)
			(primitives
				(gr_poly
					(pts
						(arc
							(start 0.1524 -0.127)
							(mid 0.137521 -0.162921)
							(end 0.1016 -0.1778)
						)
						(arc
							(start -0.1016 -0.1778)
							(mid -0.137521 -0.162921)
							(end -0.1524 -0.127)
						)
						(arc
							(start -0.1524 0.127)
							(mid -0.137521 0.162921)
							(end -0.1016 0.1778)
						)
						(arc
							(start 0.1016 0.1778)
							(mid 0.137521 0.162921)
							(end 0.1524 0.127)
						)
					)
					(width 0)
					(fill yes)
				)
			)
		)
	)
	(footprint ""
		(layer "F.Cu")
		(at 166.31158 -100.67544)
		(property "Reference" "R374"
			(at 0 0 0)
			(layer "F.SilkS")
			(hide yes)
			(effects
				(font
					(size 1.27 1.27)
				)
			)
		)
		(property "Value" "4K7R2F-GP"
			(at 0.064008 -3.993896 0)
			(unlocked yes)
			(layer "F.Fab")
			(hide yes)
			(effects
				(font
					(size 1.016 1.016)
					(thickness 0.1524)
				)
			)
		)
		(property "Device Type" "R402H16"
			(at 0.064008 -5.517896 0)
			(unlocked yes)
			(layer "F.Fab")
			(hide yes)
			(effects
				(font
					(size 1.016 1.016)
					(thickness 0.1524)
				)
			)
		)
		(duplicate_pad_numbers_are_jumpers no)
		(fp_line
			(start -0.508 -0.9398)
			(end -0.508 0.9398)
			(stroke
				(width 0.1524)
				(type default)
			)
			(layer "F.SilkS")
		)
		(fp_line
			(start 0.508 -0.9398)
			(end -0.508 -0.9398)
			(stroke
				(width 0.1524)
				(type default)
			)
			(layer "F.SilkS")
		)
		(fp_rect
			(start -0.508 0.9398)
			(end 0.508 -0.9398)
			(stroke
				(width 0)
				(type default)
			)
			(fill no)
			(layer "F.CrtYd")
		)
		(fp_rect
			(start -0.508 0.9398)
			(end 0.508 -0.9398)
			(stroke
				(width 0)
				(type default)
			)
			(fill no)
			(layer "F.Fab")
		)
		(pad "1" smd custom
			(at 0 -0.4445)
			(size 0.1397 0.1397)
			(layers "F.Cu" "F.Mask" "F.Paste")
			(net "P3V3")
			(options
				(clearance outline)
				(anchor circle)
			)
			(primitives
				(gr_poly
					(pts
						(arc
							(start -0.1778 -0.2794)
							(mid -0.249642 -0.249642)
							(end -0.2794 -0.1778)
						)
						(arc
							(start -0.2794 0.1778)
							(mid -0.249642 0.249642)
							(end -0.1778 0.2794)
						)
						(arc
							(start 0.1778 0.2794)
							(mid 0.249642 0.249642)
							(end 0.2794 0.1778)
						)
						(arc
							(start 0.2794 -0.1778)
							(mid 0.249642 -0.249642)
							(end 0.1778 -0.2794)
						)
					)
					(width 0)
					(fill yes)
				)
			)
		)
		(pad "2" smd custom
			(at 0 0.4445)
			(size 0.1397 0.1397)
			(layers "F.Cu" "F.Mask" "F.Paste")
			(net "P0V975_STAT")
			(options
				(clearance outline)
				(anchor circle)
			)
			(primitives
				(gr_poly
					(pts
						(arc
							(start -0.1778 -0.2794)
							(mid -0.249642 -0.249642)
							(end -0.2794 -0.1778)
						)
						(arc
							(start -0.2794 0.1778)
							(mid -0.249642 0.249642)
							(end -0.1778 0.2794)
						)
						(arc
							(start 0.1778 0.2794)
							(mid 0.249642 0.249642)
							(end 0.2794 0.1778)
						)
						(arc
							(start 0.2794 -0.1778)
							(mid 0.249642 -0.249642)
							(end 0.1778 -0.2794)
						)
					)
					(width 0)
					(fill yes)
				)
			)
		)
	)
	(footprint ""
		(layer "F.Cu")
		(at 176.7078 -99.8347 180)
		(property "Reference" "C663"
			(at 0 0 180)
			(layer "F.SilkS")
			(hide yes)
			(effects
				(font
					(size 1.27 1.27)
				)
			)
		)
		(property "Value" "SCD1U50V3KX-GP"
			(at 0 -2.8194 180)
			(unlocked yes)
			(layer "F.Fab")
			(hide yes)
			(effects
				(font
					(size 1.016 1.016)
					(thickness 0.1524)
				)
			)
		)
		(property "Device Type" "C603H36"
			(at 0 -4.3434 180)
			(unlocked yes)
			(layer "F.Fab")
			(hide yes)
			(effects
				(font
					(size 1.016 1.016)
					(thickness 0.1524)
				)
			)
		)
		(duplicate_pad_numbers_are_jumpers no)
		(fp_line
			(start 0.508 0)
			(end -0.508 0)
			(stroke
				(width 0.2032)
				(type default)
			)
			(layer "F.SilkS")
		)
		(fp_rect
			(start -0.5842 1.3335)
			(end 0.5842 -1.3335)
			(stroke
				(width 0)
				(type default)
			)
			(fill no)
			(layer "F.CrtYd")
		)
		(fp_rect
			(start -0.5842 1.3335)
			(end 0.5842 -1.3335)
			(stroke
				(width 0)
				(type default)
			)
			(fill no)
			(layer "F.Fab")
		)
		(pad "1" smd custom
			(at 0 -0.762 180)
			(size 0.2159 0.2159)
			(layers "F.Cu" "F.Mask" "F.Paste")
			(net "VT235_VDES_RC")
			(options
				(clearance outline)
				(anchor circle)
			)
			(primitives
				(gr_poly
					(pts
						(arc
							(start -0.3302 -0.4318)
							(mid -0.402042 -0.402042)
							(end -0.4318 -0.3302)
						)
						(arc
							(start -0.4318 0.3302)
							(mid -0.402042 0.402042)
							(end -0.3302 0.4318)
						)
						(arc
							(start 0.3302 0.4318)
							(mid 0.402042 0.402042)
							(end 0.4318 0.3302)
						)
						(arc
							(start 0.4318 -0.3302)
							(mid 0.402042 -0.402042)
							(end 0.3302 -0.4318)
						)
					)
					(width 0)
					(fill yes)
				)
			)
		)
		(pad "2" smd custom
			(at 0 0.762 180)
			(size 0.2159 0.2159)
			(layers "F.Cu" "F.Mask" "F.Paste")
			(net "VT235_VDES_RCC")
			(options
				(clearance outline)
				(anchor circle)
			)
			(primitives
				(gr_poly
					(pts
						(arc
							(start -0.3302 -0.4318)
							(mid -0.402042 -0.402042)
							(end -0.4318 -0.3302)
						)
						(arc
							(start -0.4318 0.3302)
							(mid -0.402042 0.402042)
							(end -0.3302 0.4318)
						)
						(arc
							(start 0.3302 0.4318)
							(mid 0.402042 0.402042)
							(end 0.4318 0.3302)
						)
						(arc
							(start 0.4318 -0.3302)
							(mid 0.402042 -0.402042)
							(end 0.3302 -0.4318)
						)
					)
					(width 0)
					(fill yes)
				)
			)
		)
	)
)
